(kicad_pcb
	(version 20260206)
	(generator "pcbnew")
	(generator_version "10.0")
	(general
		(thickness 1.6)
		(legacy_teardrops no)
	)
	(paper "A4")
	(title_block
		(title "Bryce Canyon_IOM_IOC_16318-2_OCP.brd")
		(comment 1 "Bryce Canyon / footprints 914-918 of 1605")
	)
	(layers
		(0 "F.Cu" signal "TOP")
		(4 "In1.Cu" signal "L2GND")
		(6 "In2.Cu" signal "L3")
		(8 "In3.Cu" signal "L4VCC")
		(10 "In4.Cu" signal "L5VCC")
		(12 "In5.Cu" signal "L6")
		(14 "In6.Cu" signal "L7GND")
		(2 "B.Cu" signal "BOTTOM")
		(9 "F.Adhes" user "F.Adhesive")
		(11 "B.Adhes" user "B.Adhesive")
		(13 "F.Paste" user "Package Geometry/Pastemask Top")
		(15 "B.Paste" user "Package Geometry/Pastemask Bottom")
		(5 "F.SilkS" user "Ref Des/Silkscreen Top")
		(7 "B.SilkS" user "Ref Des/Silkscreen Bottom")
		(1 "F.Mask" user "Board Geometry/Soldermask Top")
		(3 "B.Mask" user "Board Geometry/Soldermask Bottom")
		(17 "Dwgs.User" user "User.Drawings")
		(19 "Cmts.User" user "User.Comments")
		(21 "Eco1.User" user "User.Eco1")
		(23 "Eco2.User" user "User.Eco2")
		(25 "Edge.Cuts" user "Board Geometry/Outline")
		(27 "Margin" user)
		(31 "F.CrtYd" user "Package Geometry/Place Bound Top")
		(29 "B.CrtYd" user "Package Geometry/Place Bound Bottom")
		(35 "F.Fab" user "Ref Des/Assembly Top")
		(33 "B.Fab" user "Ref Des/Assembly Bottom")
	)
	(footprint ""
		(layer "F.Cu")
		(at 74.295 -137.922 -90)
		(property "Reference" "C32"
			(at 0 0 270)
			(layer "F.SilkS")
			(hide yes)
			(effects
				(font
					(size 1.27 1.27)
				)
			)
		)
		(property "Value" "SCD1U16V2KX-3GP"
			(at 1.1811 -2.7051 270)
			(unlocked yes)
			(layer "F.Fab")
			(hide yes)
			(effects
				(font
					(size 1.016 1.016)
					(thickness 0.1524)
				)
			)
		)
		(property "Device Type" "C402H22"
			(at 1.1811 -4.2291 270)
			(unlocked yes)
			(layer "F.Fab")
			(hide yes)
			(effects
				(font
					(size 1.016 1.016)
					(thickness 0.1524)
				)
			)
		)
		(duplicate_pad_numbers_are_jumpers no)
		(fp_rect
			(start -0.4318 0.9525)
			(end 0.4318 -0.9525)
			(stroke
				(width 0)
				(type default)
			)
			(fill no)
			(layer "F.CrtYd")
		)
		(fp_rect
			(start -0.4318 0.9525)
			(end 0.4318 -0.9525)
			(stroke
				(width 0)
				(type default)
			)
			(fill no)
			(layer "F.Fab")
		)
		(pad "1" smd custom
			(at 0 -0.4445 270)
			(size 0.1524 0.1524)
			(layers "F.Cu" "F.Mask" "F.Paste")
			(net "DEBUG_HDR_UART_SEL")
			(options
				(clearance outline)
				(anchor circle)
			)
			(primitives
				(gr_poly
					(pts
						(arc
							(start 0.3048 -0.2032)
							(mid 0.275042 -0.275042)
							(end 0.2032 -0.3048)
						)
						(arc
							(start -0.2032 -0.3048)
							(mid -0.275042 -0.275042)
							(end -0.3048 -0.2032)
						)
						(arc
							(start -0.3048 0.2032)
							(mid -0.275042 0.275042)
							(end -0.2032 0.3048)
						)
						(arc
							(start 0.2032 0.3048)
							(mid 0.275042 0.275042)
							(end 0.3048 0.2032)
						)
					)
					(width 0)
					(fill yes)
				)
			)
		)
		(pad "2" smd custom
			(at 0 0.4445 270)
			(size 0.1524 0.1524)
			(layers "F.Cu" "F.Mask" "F.Paste")
			(net "GND")
			(options
				(clearance outline)
				(anchor circle)
			)
			(primitives
				(gr_poly
					(pts
						(arc
							(start 0.3048 -0.2032)
							(mid 0.275042 -0.275042)
							(end 0.2032 -0.3048)
						)
						(arc
							(start -0.2032 -0.3048)
							(mid -0.275042 -0.275042)
							(end -0.3048 -0.2032)
						)
						(arc
							(start -0.3048 0.2032)
							(mid -0.275042 0.275042)
							(end -0.2032 0.3048)
						)
						(arc
							(start 0.2032 0.3048)
							(mid 0.275042 0.275042)
							(end 0.3048 0.2032)
						)
					)
					(width 0)
					(fill yes)
				)
			)
		)
	)
	(footprint ""
		(layer "F.Cu")
		(at 149.1742 -38.4556)
		(property "Reference" "TP178"
			(at 0 0 0)
			(layer "F.SilkS")
			(hide yes)
			(effects
				(font
					(size 1.27 1.27)
				)
			)
		)
		(property "Value" "TPAD28-2-GP"
			(at -0.0127 -1.6637 0)
			(unlocked yes)
			(layer "F.Fab")
			(hide yes)
			(effects
				(font
					(size 1.016 1.016)
					(thickness 0.1524)
				)
			)
		)
		(property "Device Type" "TPAD28"
			(at -0.0127 -3.1877 0)
			(unlocked yes)
			(layer "F.Fab")
			(hide yes)
			(effects
				(font
					(size 1.016 1.016)
					(thickness 0.1524)
				)
			)
		)
		(duplicate_pad_numbers_are_jumpers no)
		(fp_poly
			(pts
				(arc
					(start 0.3556 0)
					(mid -0.3556 0)
					(end 0.3556 0)
				)
			)
			(stroke
				(width 0)
				(type default)
			)
			(fill no)
			(layer "F.CrtYd")
		)
		(fp_poly
			(pts
				(arc
					(start 0.6096 0)
					(mid -0.6096 0)
					(end 0.6096 0)
				)
			)
			(stroke
				(width 0)
				(type default)
			)
			(fill no)
			(layer "F.Fab")
		)
		(pad "1" smd circle
			(at 0 0)
			(size 0.7112 0.7112)
			(layers "F.Cu" "F.Mask" "F.Paste")
			(net "ZDEF_EXTB_TP_A1")
		)
	)
	(footprint ""
		(layer "F.Cu")
		(at 34.294826 -181.57063 -90)
		(property "Reference" "PU2"
			(at 0 0 270)
			(layer "F.SilkS")
			(hide yes)
			(effects
				(font
					(size 1.27 1.27)
				)
			)
		)
		(property "Value" "TPS53318DQPR-GP"
			(at -5.022088 -6.851904 270)
			(unlocked yes)
			(layer "F.Fab")
			(hide yes)
			(effects
				(font
					(size 1.016 1.016)
					(thickness 0.1524)
				)
			)
		)
		(property "Device Type" "DFN22G6050-G6133H60"
			(at -5.022088 -8.375904 270)
			(unlocked yes)
			(layer "F.Fab")
			(hide yes)
			(effects
				(font
					(size 1.016 1.016)
					(thickness 0.1524)
				)
			)
		)
		(duplicate_pad_numbers_are_jumpers no)
		(fp_line
			(start -3.5052 3.5179)
			(end -2.2352 3.5179)
			(stroke
				(width 0.1524)
				(type default)
			)
			(layer "F.SilkS")
		)
		(fp_line
			(start 2.2352 3.5179)
			(end 3.5052 3.5179)
			(stroke
				(width 0.1524)
				(type default)
			)
			(layer "F.SilkS")
		)
		(fp_line
			(start 3.5052 3.5179)
			(end 3.5052 2.2479)
			(stroke
				(width 0.1524)
				(type default)
			)
			(layer "F.SilkS")
		)
		(fp_line
			(start -0.999998 3.262122)
			(end -0.999998 3.770122)
			(stroke
				(width 0.1524)
				(type default)
			)
			(layer "F.SilkS")
		)
		(fp_line
			(start 1.500124 3.262122)
			(end 1.500124 4.024122)
			(stroke
				(width 0.1524)
				(type default)
			)
			(layer "F.SilkS")
		)
		(fp_line
			(start -3.5052 2.2479)
			(end -3.5052 3.5179)
			(stroke
				(width 0.1524)
				(type default)
			)
			(layer "F.SilkS")
		)
		(fp_line
			(start -1.999996 -3.262122)
			(end -1.999996 -4.024122)
			(stroke
				(width 0.1524)
				(type default)
			)
			(layer "F.SilkS")
		)
		(fp_line
			(start 0.500126 -3.262122)
			(end 0.500126 -3.770122)
			(stroke
				(width 0.1524)
				(type default)
			)
			(layer "F.SilkS")
		)
		(fp_line
			(start -3.5052 -3.5179)
			(end -3.5052 -2.2479)
			(stroke
				(width 0.1524)
				(type default)
			)
			(layer "F.SilkS")
		)
		(fp_line
			(start -2.2352 -3.5179)
			(end -3.5052 -3.5179)
			(stroke
				(width 0.1524)
				(type default)
			)
			(layer "F.SilkS")
		)
		(fp_poly
			(pts
				(xy 3.5052 -3.5179) (xy 2.4765 -3.5179) (xy 3.5052 -2.4892)
			)
			(stroke
				(width 0)
				(type default)
			)
			(fill yes)
			(layer "F.SilkS")
		)
		(fp_rect
			(start -2.9972 2.5019)
			(end 2.9972 -2.5019)
			(stroke
				(width 0)
				(type default)
			)
			(fill no)
			(layer "F.CrtYd")
		)
		(fp_poly
			(pts
				(xy 3.556 -2.5019) (xy -2.9972 -2.5019) (xy -2.9972 2.5019) (xy 2.9972 2.5019) (xy 2.9972 -2.4892)
				(xy 3.556 -2.4892) (xy 3.556 3.5179) (xy -3.556 3.5179) (xy -3.556 -3.5179) (xy 3.556 -3.5179)
			)
			(stroke
				(width 0)
				(type default)
			)
			(fill no)
			(layer "F.CrtYd")
		)
		(fp_rect
			(start -3.556 3.5179)
			(end 3.556 -3.5179)
			(stroke
				(width 0)
				(type default)
			)
			(fill no)
			(layer "F.Fab")
		)
		(pad "1" smd rect
			(at 2.500122 -2.449322 270)
			(size 0.3048 1.1176)
			(layers "F.Cu" "F.Mask" "F.Paste")
			(net "P3V3_STBY_VFB")
		)
		(pad "2" smd rect
			(at 1.999996 -2.449322 270)
			(size 0.3048 1.1176)
			(layers "F.Cu" "F.Mask" "F.Paste")
			(net "P3V3_STBY_EN")
		)
		(pad "3" smd rect
			(at 1.500124 -2.449322 270)
			(size 0.3048 1.1176)
			(layers "F.Cu" "F.Mask" "F.Paste")
			(net "PWRGD_P3V3_STBY")
		)
		(pad "4" smd rect
			(at 0.999998 -2.449322 270)
			(size 0.3048 1.1176)
			(layers "F.Cu" "F.Mask" "F.Paste")
			(net "P3V3_VBST")
		)
		(pad "5" smd rect
			(at 0.500126 -2.449322 270)
			(size 0.3048 1.1176)
			(layers "F.Cu" "F.Mask" "F.Paste")
			(net "P3V3_STBY_ROVP")
		)
		(pad "6" smd rect
			(at 0 -2.449322 270)
			(size 0.3048 1.1176)
			(layers "F.Cu" "F.Mask" "F.Paste")
			(net "P3V3_STBY_LL")
		)
		(pad "7" smd rect
			(at -0.500126 -2.449322 270)
			(size 0.3048 1.1176)
			(layers "F.Cu" "F.Mask" "F.Paste")
			(net "P3V3_STBY_LL")
		)
		(pad "8" smd rect
			(at -0.999998 -2.449322 270)
			(size 0.3048 1.1176)
			(layers "F.Cu" "F.Mask" "F.Paste")
			(net "P3V3_STBY_LL")
		)
		(pad "9" smd rect
			(at -1.500124 -2.449322 270)
			(size 0.3048 1.1176)
			(layers "F.Cu" "F.Mask" "F.Paste")
			(net "P3V3_STBY_LL")
		)
		(pad "10" smd rect
			(at -1.999996 -2.449322 270)
			(size 0.3048 1.1176)
			(layers "F.Cu" "F.Mask" "F.Paste")
			(net "P3V3_STBY_LL")
		)
		(pad "11" smd rect
			(at -2.500122 -2.449322 270)
			(size 0.3048 1.1176)
			(layers "F.Cu" "F.Mask" "F.Paste")
			(net "P3V3_STBY_LL")
		)
		(pad "12" smd rect
			(at -2.500122 2.449322 270)
			(size 0.3048 1.1176)
			(layers "F.Cu" "F.Mask" "F.Paste")
			(net "P12V_STBY_VIN_PU2")
		)
		(pad "13" smd rect
			(at -1.999996 2.449322 270)
			(size 0.3048 1.1176)
			(layers "F.Cu" "F.Mask" "F.Paste")
			(net "P12V_STBY_VIN_PU2")
		)
		(pad "14" smd rect
			(at -1.500124 2.449322 270)
			(size 0.3048 1.1176)
			(layers "F.Cu" "F.Mask" "F.Paste")
			(net "P12V_STBY_VIN_PU2")
		)
		(pad "15" smd rect
			(at -0.999998 2.449322 270)
			(size 0.3048 1.1176)
			(layers "F.Cu" "F.Mask" "F.Paste")
			(net "P12V_STBY_VIN_PU2")
		)
		(pad "16" smd rect
			(at -0.500126 2.449322 270)
			(size 0.3048 1.1176)
			(layers "F.Cu" "F.Mask" "F.Paste")
			(net "P12V_STBY_VIN_PU2")
		)
		(pad "17" smd rect
			(at 0 2.449322 270)
			(size 0.3048 1.1176)
			(layers "F.Cu" "F.Mask" "F.Paste")
			(net "P12V_STBY_VIN_PU2")
		)
		(pad "18" smd rect
			(at 0.500126 2.449322 270)
			(size 0.3048 1.1176)
			(layers "F.Cu" "F.Mask" "F.Paste")
			(net "P3V3_STBY_VREG")
		)
		(pad "19" smd rect
			(at 0.999998 2.449322 270)
			(size 0.3048 1.1176)
			(layers "F.Cu" "F.Mask" "F.Paste")
			(net "P12V_STBY_VDD_PU2")
		)
		(pad "20" smd rect
			(at 1.500124 2.449322 270)
			(size 0.3048 1.1176)
			(layers "F.Cu" "F.Mask" "F.Paste")
			(net "P3V3_STBY_MODE")
		)
		(pad "21" smd rect
			(at 1.999996 2.449322 270)
			(size 0.3048 1.1176)
			(layers "F.Cu" "F.Mask" "F.Paste")
			(net "P3V3_STBY_TRIP")
		)
		(pad "22" smd rect
			(at 2.500122 2.449322 270)
			(size 0.3048 1.1176)
			(layers "F.Cu" "F.Mask" "F.Paste")
			(net "P3V3_STBY_RF")
		)
		(pad "23" smd custom
			(at 0 0 270)
			(size 0.83185 0.83185)
			(layers "F.Cu" "F.Mask" "F.Paste")
			(net "GND")
			(options
				(clearance outline)
				(anchor circle)
			)
			(primitives
				(gr_poly
					(pts
						(xy -2.7813 1.6637) (xy -2.7813 1.2954) (xy -3.048 1.2954) (xy -3.048 0.9525) (xy -2.7813 0.9525)
						(xy -2.7813 -0.9525) (xy -3.048 -0.9525) (xy -3.048 -1.2954) (xy -2.7813 -1.2954) (xy -2.7813 -1.6637)
						(xy 2.7813 -1.6637) (xy 2.7813 -1.2954) (xy 3.048 -1.2954) (xy 3.048 -0.9525) (xy 2.7813 -0.9525)
						(xy 2.7813 0.9525) (xy 3.048 0.9525) (xy 3.048 1.2954) (xy 2.7813 1.2954) (xy 2.7813 1.6637)
					)
					(width 0)
					(fill yes)
				)
			)
		)
	)
	(footprint ""
		(layer "F.Cu")
		(at 88.674194 -53.432456)
		(property "Reference" "PQ3"
			(at 0 0 0)
			(layer "F.SilkS")
			(hide yes)
			(effects
				(font
					(size 1.27 1.27)
				)
			)
		)
		(property "Value" "FDS8878-G-GP"
			(at -3.707384 -1.5367 0)
			(unlocked yes)
			(layer "F.Fab")
			(hide yes)
			(effects
				(font
					(size 1.016 1.016)
					(thickness 0.1524)
				)
			)
		)
		(property "Device Type" "SOIC8H69"
			(at -3.707384 -3.0607 0)
			(unlocked yes)
			(layer "F.Fab")
			(hide yes)
			(effects
				(font
					(size 1.016 1.016)
					(thickness 0.1524)
				)
			)
		)
		(duplicate_pad_numbers_are_jumpers no)
		(fp_line
			(start -2.7432 -1.4224)
			(end -2.7432 1.4224)
			(stroke
				(width 0.1524)
				(type default)
			)
			(layer "F.SilkS")
		)
		(fp_line
			(start -2.7432 1.4224)
			(end -2.6416 1.4224)
			(stroke
				(width 0.1524)
				(type default)
			)
			(layer "F.SilkS")
		)
		(fp_line
			(start -2.7432 1.4224)
			(end 2.1336 1.4224)
			(stroke
				(width 0.1524)
				(type default)
			)
			(layer "F.SilkS")
		)
		(fp_line
			(start -2.7178 -0.508)
			(end -2.1844 -0.0508)
			(stroke
				(width 0.1524)
				(type default)
			)
			(layer "F.SilkS")
		)
		(fp_line
			(start -2.6289 3.4417)
			(end -2.6289 1.4732)
			(stroke
				(width 0.381)
				(type default)
			)
			(layer "F.SilkS")
		)
		(fp_line
			(start -2.1844 -0.0508)
			(end -2.7178 0.508)
			(stroke
				(width 0.1524)
				(type default)
			)
			(layer "F.SilkS")
		)
		(fp_line
			(start 2.1336 -1.4224)
			(end -2.7432 -1.4224)
			(stroke
				(width 0.1524)
				(type default)
			)
			(layer "F.SilkS")
		)
		(fp_line
			(start 2.1336 1.4224)
			(end 2.1336 -1.4224)
			(stroke
				(width 0.1524)
				(type default)
			)
			(layer "F.SilkS")
		)
		(fp_poly
			(pts
				(xy -2.2098 -1.4224) (xy -2.2098 1.4224) (xy 2.2098 1.4224) (xy 2.2098 -1.4224)
			)
			(stroke
				(width 0)
				(type default)
			)
			(fill yes)
			(layer "F.SilkS")
		)
		(fp_rect
			(start -2.450084 2.999994)
			(end 2.450084 -2.999994)
			(stroke
				(width 0)
				(type default)
			)
			(fill no)
			(layer "F.CrtYd")
		)
		(fp_poly
			(pts
				(xy -2.8194 3.6322) (xy -2.8194 -3.6322) (xy 2.8194 -3.6322) (xy 2.8194 1.18364) (xy 2.450084 1.18364)
				(xy 2.450084 -2.999994) (xy -2.450084 -2.999994) (xy -2.450084 2.999994) (xy 2.450084 2.999994)
				(xy 2.450084 1.18618) (xy 2.8194 1.18618) (xy 2.8194 3.6322)
			)
			(stroke
				(width 0)
				(type default)
			)
			(fill no)
			(layer "F.CrtYd")
		)
		(fp_rect
			(start -2.8194 3.6322)
			(end 2.8194 -3.6322)
			(stroke
				(width 0)
				(type default)
			)
			(fill no)
			(layer "F.Fab")
		)
		(pad "1" smd rect
			(at -1.905 2.54)
			(size 0.635 1.651)
			(layers "F.Cu" "F.Mask" "F.Paste")
			(net "P3V3")
		)
		(pad "2" smd rect
			(at -0.635 2.54)
			(size 0.635 1.651)
			(layers "F.Cu" "F.Mask" "F.Paste")
			(net "P3V3")
		)
		(pad "3" smd rect
			(at 0.635 2.54)
			(size 0.635 1.651)
			(layers "F.Cu" "F.Mask" "F.Paste")
			(net "P3V3")
		)
		(pad "4" smd rect
			(at 1.905 2.54)
			(size 0.635 1.651)
			(layers "F.Cu" "F.Mask" "F.Paste")
			(net "PQ2_D")
		)
		(pad "5" smd rect
			(at 1.905 -2.54)
			(size 0.635 1.651)
			(layers "F.Cu" "F.Mask" "F.Paste")
			(net "P3V3_STBY")
		)
		(pad "6" smd rect
			(at 0.635 -2.54)
			(size 0.635 1.651)
			(layers "F.Cu" "F.Mask" "F.Paste")
			(net "P3V3_STBY")
		)
		(pad "7" smd rect
			(at -0.635 -2.54)
			(size 0.635 1.651)
			(layers "F.Cu" "F.Mask" "F.Paste")
			(net "P3V3_STBY")
		)
		(pad "8" smd rect
			(at -1.905 -2.54)
			(size 0.635 1.651)
			(layers "F.Cu" "F.Mask" "F.Paste")
			(net "P3V3_STBY")
		)
	)
	(footprint ""
		(layer "F.Cu")
		(at 90.59672 -149.190456)
		(property "Reference" "R25"
			(at 0 0 0)
			(layer "F.SilkS")
			(hide yes)
			(effects
				(font
					(size 1.27 1.27)
				)
			)
		)
		(property "Value" "15KR2F-GP"
			(at 0.064008 -3.993896 0)
			(unlocked yes)
			(layer "F.Fab")
			(hide yes)
			(effects
				(font
					(size 1.016 1.016)
					(thickness 0.1524)
				)
			)
		)
		(property "Device Type" "R402H16"
			(at 0.064008 -5.517896 0)
			(unlocked yes)
			(layer "F.Fab")
			(hide yes)
			(effects
				(font
					(size 1.016 1.016)
					(thickness 0.1524)
				)
			)
		)
		(duplicate_pad_numbers_are_jumpers no)
		(fp_line
			(start -0.508 -0.9398)
			(end -0.508 0.9398)
			(stroke
				(width 0.1524)
				(type default)
			)
			(layer "F.SilkS")
		)
		(fp_line
			(start 0.508 -0.9398)
			(end -0.508 -0.9398)
			(stroke
				(width 0.1524)
				(type default)
			)
			(layer "F.SilkS")
		)
		(fp_rect
			(start -0.508 0.9398)
			(end 0.508 -0.9398)
			(stroke
				(width 0)
				(type default)
			)
			(fill no)
			(layer "F.CrtYd")
		)
		(fp_rect
			(start -0.508 0.9398)
			(end 0.508 -0.9398)
			(stroke
				(width 0)
				(type default)
			)
			(fill no)
			(layer "F.Fab")
		)
		(pad "1" smd custom
			(at 0 -0.4445)
			(size 0.1397 0.1397)
			(layers "F.Cu" "F.Mask" "F.Paste")
			(net "USB_OCS_N1")
			(options
				(clearance outline)
				(anchor circle)
			)
			(primitives
				(gr_poly
					(pts
						(arc
							(start -0.1778 -0.2794)
							(mid -0.249642 -0.249642)
							(end -0.2794 -0.1778)
						)
						(arc
							(start -0.2794 0.1778)
							(mid -0.249642 0.249642)
							(end -0.1778 0.2794)
						)
						(arc
							(start 0.1778 0.2794)
							(mid 0.249642 0.249642)
							(end 0.2794 0.1778)
						)
						(arc
							(start 0.2794 -0.1778)
							(mid 0.249642 -0.249642)
							(end 0.1778 -0.2794)
						)
					)
					(width 0)
					(fill yes)
				)
			)
		)
		(pad "2" smd custom
			(at 0 0.4445)
			(size 0.1397 0.1397)
			(layers "F.Cu" "F.Mask" "F.Paste")
			(net "GND")
			(options
				(clearance outline)
				(anchor circle)
			)
			(primitives
				(gr_poly
					(pts
						(arc
							(start -0.1778 -0.2794)
							(mid -0.249642 -0.249642)
							(end -0.2794 -0.1778)
						)
						(arc
							(start -0.2794 0.1778)
							(mid -0.249642 0.249642)
							(end -0.1778 0.2794)
						)
						(arc
							(start 0.1778 0.2794)
							(mid 0.249642 0.249642)
							(end 0.2794 0.1778)
						)
						(arc
							(start 0.2794 -0.1778)
							(mid 0.249642 -0.249642)
							(end 0.1778 -0.2794)
						)
					)
					(width 0)
					(fill yes)
				)
			)
		)
	)
)
